FILE_TYPE=LIBRARY_PARTS;
primitive 'SCONN200_H68296001','SCONN200_H68296001_SM';
  pin
    'IO1':
      PIN_NUMBER='(1,0)';
      BIDIRECTIONAL='TRUE';
      INPUT_LOAD='(-0.01,0.01)';
      OUTPUT_LOAD='(1.0,-1.0)';
    'IO2':
      PIN_NUMBER='(2,0)';
      BIDIRECTIONAL='TRUE';
      INPUT_LOAD='(-0.01,0.01)';
      OUTPUT_LOAD='(1.0,-1.0)';
    'IO3':
      PIN_NUMBER='(3,0)';
      BIDIRECTIONAL='TRUE';
      INPUT_LOAD='(-0.01,0.01)';
      OUTPUT_LOAD='(1.0,-1.0)';
    'IO4':
      PIN_NUMBER='(4,0)';
      BIDIRECTIONAL='TRUE';
      INPUT_LOAD='(-0.01,0.01)';
      OUTPUT_LOAD='(1.0,-1.0)';
    'IO5':
      PIN_NUMBER='(5,0)';
      BIDIRECTIONAL='TRUE';
      INPUT_LOAD='(-0.01,0.01)';
      OUTPUT_LOAD='(1.0,-1.0)';
    'IO6':
      PIN_NUMBER='(6,0)';
      BIDIRECTIONAL='TRUE';
      INPUT_LOAD='(-0.01,0.01)';
      OUTPUT_LOAD='(1.0,-1.0)';
    'IO7':
      PIN_NUMBER='(7,0)';
      BIDIRECTIONAL='TRUE';
      INPUT_LOAD='(-0.01,0.01)';
      OUTPUT_LOAD='(1.0,-1.0)';
    'IO8':
      PIN_NUMBER='(8,0)';
      BIDIRECTIONAL='TRUE';
      INPUT_LOAD='(-0.01,0.01)';
      OUTPUT_LOAD='(1.0,-1.0)';
    'IO9':
      PIN_NUMBER='(9,0)';
      BIDIRECTIONAL='TRUE';
      INPUT_LOAD='(-0.01,0.01)';
      OUTPUT_LOAD='(1.0,-1.0)';
    'IO10':
      PIN_NUMBER='(10,0)';
      BIDIRECTIONAL='TRUE';
      INPUT_LOAD='(-0.01,0.01)';
      OUTPUT_LOAD='(1.0,-1.0)';
    'IO11':
      PIN_NUMBER='(11,0)';
      BIDIRECTIONAL='TRUE';
      INPUT_LOAD='(-0.01,0.01)';
      OUTPUT_LOAD='(1.0,-1.0)';
    'IO12':
      PIN_NUMBER='(12,0)';
      BIDIRECTIONAL='TRUE';
      INPUT_LOAD='(-0.01,0.01)';
      OUTPUT_LOAD='(1.0,-1.0)';
    'IO13':
      PIN_NUMBER='(13,0)';
      BIDIRECTIONAL='TRUE';
      INPUT_LOAD='(-0.01,0.01)';
      OUTPUT_LOAD='(1.0,-1.0)';
    'IO14':
      PIN_NUMBER='(14,0)';
      BIDIRECTIONAL='TRUE';
      INPUT_LOAD='(-0.01,0.01)';
      OUTPUT_LOAD='(1.0,-1.0)';
    'IO15':
      PIN_NUMBER='(15,0)';
      BIDIRECTIONAL='TRUE';
      INPUT_LOAD='(-0.01,0.01)';
      OUTPUT_LOAD='(1.0,-1.0)';
    'IO16':
      PIN_NUMBER='(16,0)';
      BIDIRECTIONAL='TRUE';
      INPUT_LOAD='(-0.01,0.01)';
      OUTPUT_LOAD='(1.0,-1.0)';
    'IO17':
      PIN_NUMBER='(17,0)';
      BIDIRECTIONAL='TRUE';
      INPUT_LOAD='(-0.01,0.01)';
      OUTPUT_LOAD='(1.0,-1.0)';
    'IO18':
      PIN_NUMBER='(18,0)';
      BIDIRECTIONAL='TRUE';
      INPUT_LOAD='(-0.01,0.01)';
      OUTPUT_LOAD='(1.0,-1.0)';
    'IO19':
      PIN_NUMBER='(19,0)';
      BIDIRECTIONAL='TRUE';
      INPUT_LOAD='(-0.01,0.01)';
      OUTPUT_LOAD='(1.0,-1.0)';
    'IO20':
      PIN_NUMBER='(20,0)';
      BIDIRECTIONAL='TRUE';
      INPUT_LOAD='(-0.01,0.01)';
      OUTPUT_LOAD='(1.0,-1.0)';
    'IO21':
      PIN_NUMBER='(21,0)';
      BIDIRECTIONAL='TRUE';
      INPUT_LOAD='(-0.01,0.01)';
      OUTPUT_LOAD='(1.0,-1.0)';
    'IO22':
      PIN_NUMBER='(22,0)';
      BIDIRECTIONAL='TRUE';
      INPUT_LOAD='(-0.01,0.01)';
      OUTPUT_LOAD='(1.0,-1.0)';
    'IO23':
      PIN_NUMBER='(23,0)';
      BIDIRECTIONAL='TRUE';
      INPUT_LOAD='(-0.01,0.01)';
      OUTPUT_LOAD='(1.0,-1.0)';
    'IO24':
      PIN_NUMBER='(24,0)';
      BIDIRECTIONAL='TRUE';
      INPUT_LOAD='(-0.01,0.01)';
      OUTPUT_LOAD='(1.0,-1.0)';
    'IO25':
      PIN_NUMBER='(25,0)';
      BIDIRECTIONAL='TRUE';
      INPUT_LOAD='(-0.01,0.01)';
      OUTPUT_LOAD='(1.0,-1.0)';
    'IO26':
      PIN_NUMBER='(26,0)';
      BIDIRECTIONAL='TRUE';
      INPUT_LOAD='(-0.01,0.01)';
      OUTPUT_LOAD='(1.0,-1.0)';
    'IO27':
      PIN_NUMBER='(27,0)';
      BIDIRECTIONAL='TRUE';
      INPUT_LOAD='(-0.01,0.01)';
      OUTPUT_LOAD='(1.0,-1.0)';
    'IO28':
      PIN_NUMBER='(28,0)';
      BIDIRECTIONAL='TRUE';
      INPUT_LOAD='(-0.01,0.01)';
      OUTPUT_LOAD='(1.0,-1.0)';
    'IO29':
      PIN_NUMBER='(29,0)';
      BIDIRECTIONAL='TRUE';
      INPUT_LOAD='(-0.01,0.01)';
      OUTPUT_LOAD='(1.0,-1.0)';
    'IO30':
      PIN_NUMBER='(30,0)';
      BIDIRECTIONAL='TRUE';
      INPUT_LOAD='(-0.01,0.01)';
      OUTPUT_LOAD='(1.0,-1.0)';
    'IO31':
      PIN_NUMBER='(31,0)';
      BIDIRECTIONAL='TRUE';
      INPUT_LOAD='(-0.01,0.01)';
      OUTPUT_LOAD='(1.0,-1.0)';
    'IO32':
      PIN_NUMBER='(32,0)';
      BIDIRECTIONAL='TRUE';
      INPUT_LOAD='(-0.01,0.01)';
      OUTPUT_LOAD='(1.0,-1.0)';
    'IO33':
      PIN_NUMBER='(33,0)';
      BIDIRECTIONAL='TRUE';
      INPUT_LOAD='(-0.01,0.01)';
      OUTPUT_LOAD='(1.0,-1.0)';
    'IO34':
      PIN_NUMBER='(34,0)';
      BIDIRECTIONAL='TRUE';
      INPUT_LOAD='(-0.01,0.01)';
      OUTPUT_LOAD='(1.0,-1.0)';
    'IO35':
      PIN_NUMBER='(35,0)';
      BIDIRECTIONAL='TRUE';
      INPUT_LOAD='(-0.01,0.01)';
      OUTPUT_LOAD='(1.0,-1.0)';
    'IO36':
      PIN_NUMBER='(36,0)';
      BIDIRECTIONAL='TRUE';
      INPUT_LOAD='(-0.01,0.01)';
      OUTPUT_LOAD='(1.0,-1.0)';
    'IO37':
      PIN_NUMBER='(37,0)';
      BIDIRECTIONAL='TRUE';
      INPUT_LOAD='(-0.01,0.01)';
      OUTPUT_LOAD='(1.0,-1.0)';
    'IO38':
      PIN_NUMBER='(38,0)';
      BIDIRECTIONAL='TRUE';
      INPUT_LOAD='(-0.01,0.01)';
      OUTPUT_LOAD='(1.0,-1.0)';
    'IO39':
      PIN_NUMBER='(39,0)';
      BIDIRECTIONAL='TRUE';
      INPUT_LOAD='(-0.01,0.01)';
      OUTPUT_LOAD='(1.0,-1.0)';
    'IO40':
      PIN_NUMBER='(40,0)';
      BIDIRECTIONAL='TRUE';
      INPUT_LOAD='(-0.01,0.01)';
      OUTPUT_LOAD='(1.0,-1.0)';
    'IO41':
      PIN_NUMBER='(41,0)';
      BIDIRECTIONAL='TRUE';
      INPUT_LOAD='(-0.01,0.01)';
      OUTPUT_LOAD='(1.0,-1.0)';
    'IO42':
      PIN_NUMBER='(42,0)';
      BIDIRECTIONAL='TRUE';
      INPUT_LOAD='(-0.01,0.01)';
      OUTPUT_LOAD='(1.0,-1.0)';
    'IO43':
      PIN_NUMBER='(43,0)';
      BIDIRECTIONAL='TRUE';
      INPUT_LOAD='(-0.01,0.01)';
      OUTPUT_LOAD='(1.0,-1.0)';
    'IO44':
      PIN_NUMBER='(44,0)';
      BIDIRECTIONAL='TRUE';
      INPUT_LOAD='(-0.01,0.01)';
      OUTPUT_LOAD='(1.0,-1.0)';
    'IO45':
      PIN_NUMBER='(45,0)';
      BIDIRECTIONAL='TRUE';
      INPUT_LOAD='(-0.01,0.01)';
      OUTPUT_LOAD='(1.0,-1.0)';
    'IO46':
      PIN_NUMBER='(46,0)';
      BIDIRECTIONAL='TRUE';
      INPUT_LOAD='(-0.01,0.01)';
      OUTPUT_LOAD='(1.0,-1.0)';
    'IO47':
      PIN_NUMBER='(47,0)';
      BIDIRECTIONAL='TRUE';
      INPUT_LOAD='(-0.01,0.01)';
      OUTPUT_LOAD='(1.0,-1.0)';
    'IO48':
      PIN_NUMBER='(48,0)';
      BIDIRECTIONAL='TRUE';
      INPUT_LOAD='(-0.01,0.01)';
      OUTPUT_LOAD='(1.0,-1.0)';
    'IO49':
      PIN_NUMBER='(49,0)';
      BIDIRECTIONAL='TRUE';
      INPUT_LOAD='(-0.01,0.01)';
      OUTPUT_LOAD='(1.0,-1.0)';
    'IO50':
      PIN_NUMBER='(50,0)';
      BIDIRECTIONAL='TRUE';
      INPUT_LOAD='(-0.01,0.01)';
      OUTPUT_LOAD='(1.0,-1.0)';
    'IO51':
      PIN_NUMBER='(51,0)';
      BIDIRECTIONAL='TRUE';
      INPUT_LOAD='(-0.01,0.01)';
      OUTPUT_LOAD='(1.0,-1.0)';
    'IO52':
      PIN_NUMBER='(52,0)';
      BIDIRECTIONAL='TRUE';
      INPUT_LOAD='(-0.01,0.01)';
      OUTPUT_LOAD='(1.0,-1.0)';
    'IO53':
      PIN_NUMBER='(53,0)';
      BIDIRECTIONAL='TRUE';
      INPUT_LOAD='(-0.01,0.01)';
      OUTPUT_LOAD='(1.0,-1.0)';
    'IO54':
      PIN_NUMBER='(54,0)';
      BIDIRECTIONAL='TRUE';
      INPUT_LOAD='(-0.01,0.01)';
      OUTPUT_LOAD='(1.0,-1.0)';
    'IO55':
      PIN_NUMBER='(55,0)';
      BIDIRECTIONAL='TRUE';
      INPUT_LOAD='(-0.01,0.01)';
      OUTPUT_LOAD='(1.0,-1.0)';
    'IO56':
      PIN_NUMBER='(56,0)';
      BIDIRECTIONAL='TRUE';
      INPUT_LOAD='(-0.01,0.01)';
      OUTPUT_LOAD='(1.0,-1.0)';
    'IO57':
      PIN_NUMBER='(57,0)';
      BIDIRECTIONAL='TRUE';
      INPUT_LOAD='(-0.01,0.01)';
      OUTPUT_LOAD='(1.0,-1.0)';
    'IO58':
      PIN_NUMBER='(58,0)';
      BIDIRECTIONAL='TRUE';
      INPUT_LOAD='(-0.01,0.01)';
      OUTPUT_LOAD='(1.0,-1.0)';
    'IO59':
      PIN_NUMBER='(59,0)';
      BIDIRECTIONAL='TRUE';
      INPUT_LOAD='(-0.01,0.01)';
      OUTPUT_LOAD='(1.0,-1.0)';
    'IO60':
      PIN_NUMBER='(60,0)';
      BIDIRECTIONAL='TRUE';
      INPUT_LOAD='(-0.01,0.01)';
      OUTPUT_LOAD='(1.0,-1.0)';
    'IO61':
      PIN_NUMBER='(61,0)';
      BIDIRECTIONAL='TRUE';
      INPUT_LOAD='(-0.01,0.01)';
      OUTPUT_LOAD='(1.0,-1.0)';
    'IO62':
      PIN_NUMBER='(62,0)';
      BIDIRECTIONAL='TRUE';
      INPUT_LOAD='(-0.01,0.01)';
      OUTPUT_LOAD='(1.0,-1.0)';
    'IO63':
      PIN_NUMBER='(63,0)';
      BIDIRECTIONAL='TRUE';
      INPUT_LOAD='(-0.01,0.01)';
      OUTPUT_LOAD='(1.0,-1.0)';
    'IO64':
      PIN_NUMBER='(64,0)';
      BIDIRECTIONAL='TRUE';
      INPUT_LOAD='(-0.01,0.01)';
      OUTPUT_LOAD='(1.0,-1.0)';
    'IO65':
      PIN_NUMBER='(65,0)';
      BIDIRECTIONAL='TRUE';
      INPUT_LOAD='(-0.01,0.01)';
      OUTPUT_LOAD='(1.0,-1.0)';
    'IO66':
      PIN_NUMBER='(66,0)';
      BIDIRECTIONAL='TRUE';
      INPUT_LOAD='(-0.01,0.01)';
      OUTPUT_LOAD='(1.0,-1.0)';
    'IO67':
      PIN_NUMBER='(67,0)';
      BIDIRECTIONAL='TRUE';
      INPUT_LOAD='(-0.01,0.01)';
      OUTPUT_LOAD='(1.0,-1.0)';
    'IO68':
      PIN_NUMBER='(68,0)';
      BIDIRECTIONAL='TRUE';
      INPUT_LOAD='(-0.01,0.01)';
      OUTPUT_LOAD='(1.0,-1.0)';
    'IO69':
      PIN_NUMBER='(69,0)';
      BIDIRECTIONAL='TRUE';
      INPUT_LOAD='(-0.01,0.01)';
      OUTPUT_LOAD='(1.0,-1.0)';
    'IO70':
      PIN_NUMBER='(70,0)';
      BIDIRECTIONAL='TRUE';
      INPUT_LOAD='(-0.01,0.01)';
      OUTPUT_LOAD='(1.0,-1.0)';
    'IO71':
      PIN_NUMBER='(71,0)';
      BIDIRECTIONAL='TRUE';
      INPUT_LOAD='(-0.01,0.01)';
      OUTPUT_LOAD='(1.0,-1.0)';
    'IO72':
      PIN_NUMBER='(72,0)';
      BIDIRECTIONAL='TRUE';
      INPUT_LOAD='(-0.01,0.01)';
      OUTPUT_LOAD='(1.0,-1.0)';
    'IO73':
      PIN_NUMBER='(73,0)';
      BIDIRECTIONAL='TRUE';
      INPUT_LOAD='(-0.01,0.01)';
      OUTPUT_LOAD='(1.0,-1.0)';
    'IO74':
      PIN_NUMBER='(74,0)';
      BIDIRECTIONAL='TRUE';
      INPUT_LOAD='(-0.01,0.01)';
      OUTPUT_LOAD='(1.0,-1.0)';
    'IO75':
      PIN_NUMBER='(75,0)';
      BIDIRECTIONAL='TRUE';
      INPUT_LOAD='(-0.01,0.01)';
      OUTPUT_LOAD='(1.0,-1.0)';
    'IO76':
      PIN_NUMBER='(76,0)';
      BIDIRECTIONAL='TRUE';
      INPUT_LOAD='(-0.01,0.01)';
      OUTPUT_LOAD='(1.0,-1.0)';
    'IO77':
      PIN_NUMBER='(77,0)';
      BIDIRECTIONAL='TRUE';
      INPUT_LOAD='(-0.01,0.01)';
      OUTPUT_LOAD='(1.0,-1.0)';
    'IO78':
      PIN_NUMBER='(78,0)';
      BIDIRECTIONAL='TRUE';
      INPUT_LOAD='(-0.01,0.01)';
      OUTPUT_LOAD='(1.0,-1.0)';
    'IO79':
      PIN_NUMBER='(79,0)';
      BIDIRECTIONAL='TRUE';
      INPUT_LOAD='(-0.01,0.01)';
      OUTPUT_LOAD='(1.0,-1.0)';
    'IO80':
      PIN_NUMBER='(80,0)';
      BIDIRECTIONAL='TRUE';
      INPUT_LOAD='(-0.01,0.01)';
      OUTPUT_LOAD='(1.0,-1.0)';
    'IO81':
      PIN_NUMBER='(81,0)';
      BIDIRECTIONAL='TRUE';
      INPUT_LOAD='(-0.01,0.01)';
      OUTPUT_LOAD='(1.0,-1.0)';
    'IO82':
      PIN_NUMBER='(82,0)';
      BIDIRECTIONAL='TRUE';
      INPUT_LOAD='(-0.01,0.01)';
      OUTPUT_LOAD='(1.0,-1.0)';
    'IO83':
      PIN_NUMBER='(83,0)';
      BIDIRECTIONAL='TRUE';
      INPUT_LOAD='(-0.01,0.01)';
      OUTPUT_LOAD='(1.0,-1.0)';
    'IO84':
      PIN_NUMBER='(84,0)';
      BIDIRECTIONAL='TRUE';
      INPUT_LOAD='(-0.01,0.01)';
      OUTPUT_LOAD='(1.0,-1.0)';
    'IO85':
      PIN_NUMBER='(85,0)';
      BIDIRECTIONAL='TRUE';
      INPUT_LOAD='(-0.01,0.01)';
      OUTPUT_LOAD='(1.0,-1.0)';
    'IO86':
      PIN_NUMBER='(86,0)';
      BIDIRECTIONAL='TRUE';
      INPUT_LOAD='(-0.01,0.01)';
      OUTPUT_LOAD='(1.0,-1.0)';
    'IO87':
      PIN_NUMBER='(87,0)';
      BIDIRECTIONAL='TRUE';
      INPUT_LOAD='(-0.01,0.01)';
      OUTPUT_LOAD='(1.0,-1.0)';
    'IO88':
      PIN_NUMBER='(88,0)';
      BIDIRECTIONAL='TRUE';
      INPUT_LOAD='(-0.01,0.01)';
      OUTPUT_LOAD='(1.0,-1.0)';
    'IO89':
      PIN_NUMBER='(89,0)';
      BIDIRECTIONAL='TRUE';
      INPUT_LOAD='(-0.01,0.01)';
      OUTPUT_LOAD='(1.0,-1.0)';
    'IO90':
      PIN_NUMBER='(90,0)';
      BIDIRECTIONAL='TRUE';
      INPUT_LOAD='(-0.01,0.01)';
      OUTPUT_LOAD='(1.0,-1.0)';
    'IO91':
      PIN_NUMBER='(91,0)';
      BIDIRECTIONAL='TRUE';
      INPUT_LOAD='(-0.01,0.01)';
      OUTPUT_LOAD='(1.0,-1.0)';
    'IO92':
      PIN_NUMBER='(92,0)';
      BIDIRECTIONAL='TRUE';
      INPUT_LOAD='(-0.01,0.01)';
      OUTPUT_LOAD='(1.0,-1.0)';
    'IO93':
      PIN_NUMBER='(93,0)';
      BIDIRECTIONAL='TRUE';
      INPUT_LOAD='(-0.01,0.01)';
      OUTPUT_LOAD='(1.0,-1.0)';
    'IO94':
      PIN_NUMBER='(94,0)';
      BIDIRECTIONAL='TRUE';
      INPUT_LOAD='(-0.01,0.01)';
      OUTPUT_LOAD='(1.0,-1.0)';
    'IO95':
      PIN_NUMBER='(95,0)';
      BIDIRECTIONAL='TRUE';
      INPUT_LOAD='(-0.01,0.01)';
      OUTPUT_LOAD='(1.0,-1.0)';
    'IO96':
      PIN_NUMBER='(96,0)';
      BIDIRECTIONAL='TRUE';
      INPUT_LOAD='(-0.01,0.01)';
      OUTPUT_LOAD='(1.0,-1.0)';
    'IO97':
      PIN_NUMBER='(97,0)';
      BIDIRECTIONAL='TRUE';
      INPUT_LOAD='(-0.01,0.01)';
      OUTPUT_LOAD='(1.0,-1.0)';
    'IO98':
      PIN_NUMBER='(98,0)';
      BIDIRECTIONAL='TRUE';
      INPUT_LOAD='(-0.01,0.01)';
      OUTPUT_LOAD='(1.0,-1.0)';
    'IO99':
      PIN_NUMBER='(99,0)';
      BIDIRECTIONAL='TRUE';
      INPUT_LOAD='(-0.01,0.01)';
      OUTPUT_LOAD='(1.0,-1.0)';
    'IO100':
      PIN_NUMBER='(100,0)';
      BIDIRECTIONAL='TRUE';
      INPUT_LOAD='(-0.01,0.01)';
      OUTPUT_LOAD='(1.0,-1.0)';
    'IO101':
      PIN_NUMBER='(0,101)';
      BIDIRECTIONAL='TRUE';
      INPUT_LOAD='(-0.01,0.01)';
      OUTPUT_LOAD='(1.0,-1.0)';
    'IO102':
      PIN_NUMBER='(0,102)';
      BIDIRECTIONAL='TRUE';
      INPUT_LOAD='(-0.01,0.01)';
      OUTPUT_LOAD='(1.0,-1.0)';
    'IO103':
      PIN_NUMBER='(0,103)';
      BIDIRECTIONAL='TRUE';
      INPUT_LOAD='(-0.01,0.01)';
      OUTPUT_LOAD='(1.0,-1.0)';
    'IO104':
      PIN_NUMBER='(0,104)';
      BIDIRECTIONAL='TRUE';
      INPUT_LOAD='(-0.01,0.01)';
      OUTPUT_LOAD='(1.0,-1.0)';
    'IO105':
      PIN_NUMBER='(0,105)';
      BIDIRECTIONAL='TRUE';
      INPUT_LOAD='(-0.01,0.01)';
      OUTPUT_LOAD='(1.0,-1.0)';
    'IO106':
      PIN_NUMBER='(0,106)';
      BIDIRECTIONAL='TRUE';
      INPUT_LOAD='(-0.01,0.01)';
      OUTPUT_LOAD='(1.0,-1.0)';
    'IO107':
      PIN_NUMBER='(0,107)';
      BIDIRECTIONAL='TRUE';
      INPUT_LOAD='(-0.01,0.01)';
      OUTPUT_LOAD='(1.0,-1.0)';
    'IO108':
      PIN_NUMBER='(0,108)';
      BIDIRECTIONAL='TRUE';
      INPUT_LOAD='(-0.01,0.01)';
      OUTPUT_LOAD='(1.0,-1.0)';
    'IO109':
      PIN_NUMBER='(0,109)';
      BIDIRECTIONAL='TRUE';
      INPUT_LOAD='(-0.01,0.01)';
      OUTPUT_LOAD='(1.0,-1.0)';
    'IO110':
      PIN_NUMBER='(0,110)';
      BIDIRECTIONAL='TRUE';
      INPUT_LOAD='(-0.01,0.01)';
      OUTPUT_LOAD='(1.0,-1.0)';
    'IO111':
      PIN_NUMBER='(0,111)';
      BIDIRECTIONAL='TRUE';
      INPUT_LOAD='(-0.01,0.01)';
      OUTPUT_LOAD='(1.0,-1.0)';
    'IO112':
      PIN_NUMBER='(0,112)';
      BIDIRECTIONAL='TRUE';
      INPUT_LOAD='(-0.01,0.01)';
      OUTPUT_LOAD='(1.0,-1.0)';
    'IO113':
      PIN_NUMBER='(0,113)';
      BIDIRECTIONAL='TRUE';
      INPUT_LOAD='(-0.01,0.01)';
      OUTPUT_LOAD='(1.0,-1.0)';
    'IO114':
      PIN_NUMBER='(0,114)';
      BIDIRECTIONAL='TRUE';
      INPUT_LOAD='(-0.01,0.01)';
      OUTPUT_LOAD='(1.0,-1.0)';
    'IO115':
      PIN_NUMBER='(0,115)';
      BIDIRECTIONAL='TRUE';
      INPUT_LOAD='(-0.01,0.01)';
      OUTPUT_LOAD='(1.0,-1.0)';
    'IO116':
      PIN_NUMBER='(0,116)';
      BIDIRECTIONAL='TRUE';
      INPUT_LOAD='(-0.01,0.01)';
      OUTPUT_LOAD='(1.0,-1.0)';
    'IO117':
      PIN_NUMBER='(0,117)';
      BIDIRECTIONAL='TRUE';
      INPUT_LOAD='(-0.01,0.01)';
      OUTPUT_LOAD='(1.0,-1.0)';
    'IO118':
      PIN_NUMBER='(0,118)';
      BIDIRECTIONAL='TRUE';
      INPUT_LOAD='(-0.01,0.01)';
      OUTPUT_LOAD='(1.0,-1.0)';
    'IO119':
      PIN_NUMBER='(0,119)';
      BIDIRECTIONAL='TRUE';
      INPUT_LOAD='(-0.01,0.01)';
      OUTPUT_LOAD='(1.0,-1.0)';
    'IO120':
      PIN_NUMBER='(0,120)';
      BIDIRECTIONAL='TRUE';
      INPUT_LOAD='(-0.01,0.01)';
      OUTPUT_LOAD='(1.0,-1.0)';
    'IO121':
      PIN_NUMBER='(0,121)';
      BIDIRECTIONAL='TRUE';
      INPUT_LOAD='(-0.01,0.01)';
      OUTPUT_LOAD='(1.0,-1.0)';
    'IO122':
      PIN_NUMBER='(0,122)';
      BIDIRECTIONAL='TRUE';
      INPUT_LOAD='(-0.01,0.01)';
      OUTPUT_LOAD='(1.0,-1.0)';
    'IO123':
      PIN_NUMBER='(0,123)';
      BIDIRECTIONAL='TRUE';
      INPUT_LOAD='(-0.01,0.01)';
      OUTPUT_LOAD='(1.0,-1.0)';
    'IO124':
      PIN_NUMBER='(0,124)';
      BIDIRECTIONAL='TRUE';
      INPUT_LOAD='(-0.01,0.01)';
      OUTPUT_LOAD='(1.0,-1.0)';
    'IO125':
      PIN_NUMBER='(0,125)';
      BIDIRECTIONAL='TRUE';
      INPUT_LOAD='(-0.01,0.01)';
      OUTPUT_LOAD='(1.0,-1.0)';
    'IO126':
      PIN_NUMBER='(0,126)';
      BIDIRECTIONAL='TRUE';
      INPUT_LOAD='(-0.01,0.01)';
      OUTPUT_LOAD='(1.0,-1.0)';
    'IO127':
      PIN_NUMBER='(0,127)';
      BIDIRECTIONAL='TRUE';
      INPUT_LOAD='(-0.01,0.01)';
      OUTPUT_LOAD='(1.0,-1.0)';
    'IO128':
      PIN_NUMBER='(0,128)';
      BIDIRECTIONAL='TRUE';
      INPUT_LOAD='(-0.01,0.01)';
      OUTPUT_LOAD='(1.0,-1.0)';
    'IO129':
      PIN_NUMBER='(0,129)';
      BIDIRECTIONAL='TRUE';
      INPUT_LOAD='(-0.01,0.01)';
      OUTPUT_LOAD='(1.0,-1.0)';
    'IO130':
      PIN_NUMBER='(0,130)';
      BIDIRECTIONAL='TRUE';
      INPUT_LOAD='(-0.01,0.01)';
      OUTPUT_LOAD='(1.0,-1.0)';
    'IO131':
      PIN_NUMBER='(0,131)';
      BIDIRECTIONAL='TRUE';
      INPUT_LOAD='(-0.01,0.01)';
      OUTPUT_LOAD='(1.0,-1.0)';
    'IO132':
      PIN_NUMBER='(0,132)';
      BIDIRECTIONAL='TRUE';
      INPUT_LOAD='(-0.01,0.01)';
      OUTPUT_LOAD='(1.0,-1.0)';
    'IO133':
      PIN_NUMBER='(0,133)';
      BIDIRECTIONAL='TRUE';
      INPUT_LOAD='(-0.01,0.01)';
      OUTPUT_LOAD='(1.0,-1.0)';
    'IO134':
      PIN_NUMBER='(0,134)';
      BIDIRECTIONAL='TRUE';
      INPUT_LOAD='(-0.01,0.01)';
      OUTPUT_LOAD='(1.0,-1.0)';
    'IO135':
      PIN_NUMBER='(0,135)';
      BIDIRECTIONAL='TRUE';
      INPUT_LOAD='(-0.01,0.01)';
      OUTPUT_LOAD='(1.0,-1.0)';
    'IO136':
      PIN_NUMBER='(0,136)';
      BIDIRECTIONAL='TRUE';
      INPUT_LOAD='(-0.01,0.01)';
      OUTPUT_LOAD='(1.0,-1.0)';
    'IO137':
      PIN_NUMBER='(0,137)';
      BIDIRECTIONAL='TRUE';
      INPUT_LOAD='(-0.01,0.01)';
      OUTPUT_LOAD='(1.0,-1.0)';
    'IO138':
      PIN_NUMBER='(0,138)';
      BIDIRECTIONAL='TRUE';
      INPUT_LOAD='(-0.01,0.01)';
      OUTPUT_LOAD='(1.0,-1.0)';
    'IO139':
      PIN_NUMBER='(0,139)';
      BIDIRECTIONAL='TRUE';
      INPUT_LOAD='(-0.01,0.01)';
      OUTPUT_LOAD='(1.0,-1.0)';
    'IO140':
      PIN_NUMBER='(0,140)';
      BIDIRECTIONAL='TRUE';
      INPUT_LOAD='(-0.01,0.01)';
      OUTPUT_LOAD='(1.0,-1.0)';
    'IO141':
      PIN_NUMBER='(0,141)';
      BIDIRECTIONAL='TRUE';
      INPUT_LOAD='(-0.01,0.01)';
      OUTPUT_LOAD='(1.0,-1.0)';
    'IO142':
      PIN_NUMBER='(0,142)';
      BIDIRECTIONAL='TRUE';
      INPUT_LOAD='(-0.01,0.01)';
      OUTPUT_LOAD='(1.0,-1.0)';
    'IO143':
      PIN_NUMBER='(0,143)';
      BIDIRECTIONAL='TRUE';
      INPUT_LOAD='(-0.01,0.01)';
      OUTPUT_LOAD='(1.0,-1.0)';
    'IO144':
      PIN_NUMBER='(0,144)';
      BIDIRECTIONAL='TRUE';
      INPUT_LOAD='(-0.01,0.01)';
      OUTPUT_LOAD='(1.0,-1.0)';
    'IO145':
      PIN_NUMBER='(0,145)';
      BIDIRECTIONAL='TRUE';
      INPUT_LOAD='(-0.01,0.01)';
      OUTPUT_LOAD='(1.0,-1.0)';
    'IO146':
      PIN_NUMBER='(0,146)';
      BIDIRECTIONAL='TRUE';
      INPUT_LOAD='(-0.01,0.01)';
      OUTPUT_LOAD='(1.0,-1.0)';
    'IO147':
      PIN_NUMBER='(0,147)';
      BIDIRECTIONAL='TRUE';
      INPUT_LOAD='(-0.01,0.01)';
      OUTPUT_LOAD='(1.0,-1.0)';
    'IO148':
      PIN_NUMBER='(0,148)';
      BIDIRECTIONAL='TRUE';
      INPUT_LOAD='(-0.01,0.01)';
      OUTPUT_LOAD='(1.0,-1.0)';
    'IO149':
      PIN_NUMBER='(0,149)';
      BIDIRECTIONAL='TRUE';
      INPUT_LOAD='(-0.01,0.01)';
      OUTPUT_LOAD='(1.0,-1.0)';
    'IO150':
      PIN_NUMBER='(0,150)';
      BIDIRECTIONAL='TRUE';
      INPUT_LOAD='(-0.01,0.01)';
      OUTPUT_LOAD='(1.0,-1.0)';
    'IO151':
      PIN_NUMBER='(0,151)';
      BIDIRECTIONAL='TRUE';
      INPUT_LOAD='(-0.01,0.01)';
      OUTPUT_LOAD='(1.0,-1.0)';
    'IO152':
      PIN_NUMBER='(0,152)';
      BIDIRECTIONAL='TRUE';
      INPUT_LOAD='(-0.01,0.01)';
      OUTPUT_LOAD='(1.0,-1.0)';
    'IO153':
      PIN_NUMBER='(0,153)';
      BIDIRECTIONAL='TRUE';
      INPUT_LOAD='(-0.01,0.01)';
      OUTPUT_LOAD='(1.0,-1.0)';
    'IO154':
      PIN_NUMBER='(0,154)';
      BIDIRECTIONAL='TRUE';
      INPUT_LOAD='(-0.01,0.01)';
      OUTPUT_LOAD='(1.0,-1.0)';
    'IO155':
      PIN_NUMBER='(0,155)';
      BIDIRECTIONAL='TRUE';
      INPUT_LOAD='(-0.01,0.01)';
      OUTPUT_LOAD='(1.0,-1.0)';
    'IO156':
      PIN_NUMBER='(0,156)';
      BIDIRECTIONAL='TRUE';
      INPUT_LOAD='(-0.01,0.01)';
      OUTPUT_LOAD='(1.0,-1.0)';
    'IO157':
      PIN_NUMBER='(0,157)';
      BIDIRECTIONAL='TRUE';
      INPUT_LOAD='(-0.01,0.01)';
      OUTPUT_LOAD='(1.0,-1.0)';
    'IO158':
      PIN_NUMBER='(0,158)';
      BIDIRECTIONAL='TRUE';
      INPUT_LOAD='(-0.01,0.01)';
      OUTPUT_LOAD='(1.0,-1.0)';
    'IO159':
      PIN_NUMBER='(0,159)';
      BIDIRECTIONAL='TRUE';
      INPUT_LOAD='(-0.01,0.01)';
      OUTPUT_LOAD='(1.0,-1.0)';
    'IO160':
      PIN_NUMBER='(0,160)';
      BIDIRECTIONAL='TRUE';
      INPUT_LOAD='(-0.01,0.01)';
      OUTPUT_LOAD='(1.0,-1.0)';
    'IO161':
      PIN_NUMBER='(0,161)';
      BIDIRECTIONAL='TRUE';
      INPUT_LOAD='(-0.01,0.01)';
      OUTPUT_LOAD='(1.0,-1.0)';
    'IO162':
      PIN_NUMBER='(0,162)';
      BIDIRECTIONAL='TRUE';
      INPUT_LOAD='(-0.01,0.01)';
      OUTPUT_LOAD='(1.0,-1.0)';
    'IO163':
      PIN_NUMBER='(0,163)';
      BIDIRECTIONAL='TRUE';
      INPUT_LOAD='(-0.01,0.01)';
      OUTPUT_LOAD='(1.0,-1.0)';
    'IO164':
      PIN_NUMBER='(0,164)';
      BIDIRECTIONAL='TRUE';
      INPUT_LOAD='(-0.01,0.01)';
      OUTPUT_LOAD='(1.0,-1.0)';
    'IO165':
      PIN_NUMBER='(0,165)';
      BIDIRECTIONAL='TRUE';
      INPUT_LOAD='(-0.01,0.01)';
      OUTPUT_LOAD='(1.0,-1.0)';
    'IO166':
      PIN_NUMBER='(0,166)';
      BIDIRECTIONAL='TRUE';
      INPUT_LOAD='(-0.01,0.01)';
      OUTPUT_LOAD='(1.0,-1.0)';
    'IO167':
      PIN_NUMBER='(0,167)';
      BIDIRECTIONAL='TRUE';
      INPUT_LOAD='(-0.01,0.01)';
      OUTPUT_LOAD='(1.0,-1.0)';
    'IO168':
      PIN_NUMBER='(0,168)';
      BIDIRECTIONAL='TRUE';
      INPUT_LOAD='(-0.01,0.01)';
      OUTPUT_LOAD='(1.0,-1.0)';
    'IO169':
      PIN_NUMBER='(0,169)';
      BIDIRECTIONAL='TRUE';
      INPUT_LOAD='(-0.01,0.01)';
      OUTPUT_LOAD='(1.0,-1.0)';
    'IO170':
      PIN_NUMBER='(0,170)';
      BIDIRECTIONAL='TRUE';
      INPUT_LOAD='(-0.01,0.01)';
      OUTPUT_LOAD='(1.0,-1.0)';
    'IO171':
      PIN_NUMBER='(0,171)';
      BIDIRECTIONAL='TRUE';
      INPUT_LOAD='(-0.01,0.01)';
      OUTPUT_LOAD='(1.0,-1.0)';
    'IO172':
      PIN_NUMBER='(0,172)';
      BIDIRECTIONAL='TRUE';
      INPUT_LOAD='(-0.01,0.01)';
      OUTPUT_LOAD='(1.0,-1.0)';
    'IO173':
      PIN_NUMBER='(0,173)';
      BIDIRECTIONAL='TRUE';
      INPUT_LOAD='(-0.01,0.01)';
      OUTPUT_LOAD='(1.0,-1.0)';
    'IO174':
      PIN_NUMBER='(0,174)';
      BIDIRECTIONAL='TRUE';
      INPUT_LOAD='(-0.01,0.01)';
      OUTPUT_LOAD='(1.0,-1.0)';
    'IO175':
      PIN_NUMBER='(0,175)';
      BIDIRECTIONAL='TRUE';
      INPUT_LOAD='(-0.01,0.01)';
      OUTPUT_LOAD='(1.0,-1.0)';
    'IO176':
      PIN_NUMBER='(0,176)';
      BIDIRECTIONAL='TRUE';
      INPUT_LOAD='(-0.01,0.01)';
      OUTPUT_LOAD='(1.0,-1.0)';
    'IO177':
      PIN_NUMBER='(0,177)';
      BIDIRECTIONAL='TRUE';
      INPUT_LOAD='(-0.01,0.01)';
      OUTPUT_LOAD='(1.0,-1.0)';
    'IO178':
      PIN_NUMBER='(0,178)';
      BIDIRECTIONAL='TRUE';
      INPUT_LOAD='(-0.01,0.01)';
      OUTPUT_LOAD='(1.0,-1.0)';
    'IO179':
      PIN_NUMBER='(0,179)';
      BIDIRECTIONAL='TRUE';
      INPUT_LOAD='(-0.01,0.01)';
      OUTPUT_LOAD='(1.0,-1.0)';
    'IO180':
      PIN_NUMBER='(0,180)';
      BIDIRECTIONAL='TRUE';
      INPUT_LOAD='(-0.01,0.01)';
      OUTPUT_LOAD='(1.0,-1.0)';
    'IO181':
      PIN_NUMBER='(0,181)';
      BIDIRECTIONAL='TRUE';
      INPUT_LOAD='(-0.01,0.01)';
      OUTPUT_LOAD='(1.0,-1.0)';
    'IO182':
      PIN_NUMBER='(0,182)';
      BIDIRECTIONAL='TRUE';
      INPUT_LOAD='(-0.01,0.01)';
      OUTPUT_LOAD='(1.0,-1.0)';
    'IO183':
      PIN_NUMBER='(0,183)';
      BIDIRECTIONAL='TRUE';
      INPUT_LOAD='(-0.01,0.01)';
      OUTPUT_LOAD='(1.0,-1.0)';
    'IO184':
      PIN_NUMBER='(0,184)';
      BIDIRECTIONAL='TRUE';
      INPUT_LOAD='(-0.01,0.01)';
      OUTPUT_LOAD='(1.0,-1.0)';
    'IO185':
      PIN_NUMBER='(0,185)';
      BIDIRECTIONAL='TRUE';
      INPUT_LOAD='(-0.01,0.01)';
      OUTPUT_LOAD='(1.0,-1.0)';
    'IO186':
      PIN_NUMBER='(0,186)';
      BIDIRECTIONAL='TRUE';
      INPUT_LOAD='(-0.01,0.01)';
      OUTPUT_LOAD='(1.0,-1.0)';
    'IO187':
      PIN_NUMBER='(0,187)';
      BIDIRECTIONAL='TRUE';
      INPUT_LOAD='(-0.01,0.01)';
      OUTPUT_LOAD='(1.0,-1.0)';
    'IO188':
      PIN_NUMBER='(0,188)';
      BIDIRECTIONAL='TRUE';
      INPUT_LOAD='(-0.01,0.01)';
      OUTPUT_LOAD='(1.0,-1.0)';
    'IO189':
      PIN_NUMBER='(0,189)';
      BIDIRECTIONAL='TRUE';
      INPUT_LOAD='(-0.01,0.01)';
      OUTPUT_LOAD='(1.0,-1.0)';
    'IO190':
      PIN_NUMBER='(0,190)';
      BIDIRECTIONAL='TRUE';
      INPUT_LOAD='(-0.01,0.01)';
      OUTPUT_LOAD='(1.0,-1.0)';
    'IO191':
      PIN_NUMBER='(0,191)';
      BIDIRECTIONAL='TRUE';
      INPUT_LOAD='(-0.01,0.01)';
      OUTPUT_LOAD='(1.0,-1.0)';
    'IO192':
      PIN_NUMBER='(0,192)';
      BIDIRECTIONAL='TRUE';
      INPUT_LOAD='(-0.01,0.01)';
      OUTPUT_LOAD='(1.0,-1.0)';
    'IO193':
      PIN_NUMBER='(0,193)';
      BIDIRECTIONAL='TRUE';
      INPUT_LOAD='(-0.01,0.01)';
      OUTPUT_LOAD='(1.0,-1.0)';
    'IO194':
      PIN_NUMBER='(0,194)';
      BIDIRECTIONAL='TRUE';
      INPUT_LOAD='(-0.01,0.01)';
      OUTPUT_LOAD='(1.0,-1.0)';
    'IO195':
      PIN_NUMBER='(0,195)';
      BIDIRECTIONAL='TRUE';
      INPUT_LOAD='(-0.01,0.01)';
      OUTPUT_LOAD='(1.0,-1.0)';
    'IO196':
      PIN_NUMBER='(0,196)';
      BIDIRECTIONAL='TRUE';
      INPUT_LOAD='(-0.01,0.01)';
      OUTPUT_LOAD='(1.0,-1.0)';
    'IO197':
      PIN_NUMBER='(0,197)';
      BIDIRECTIONAL='TRUE';
      INPUT_LOAD='(-0.01,0.01)';
      OUTPUT_LOAD='(1.0,-1.0)';
    'IO198':
      PIN_NUMBER='(0,198)';
      BIDIRECTIONAL='TRUE';
      INPUT_LOAD='(-0.01,0.01)';
      OUTPUT_LOAD='(1.0,-1.0)';
    'IO199':
      PIN_NUMBER='(0,199)';
      BIDIRECTIONAL='TRUE';
      INPUT_LOAD='(-0.01,0.01)';
      OUTPUT_LOAD='(1.0,-1.0)';
    'IO200':
      PIN_NUMBER='(0,200)';
      BIDIRECTIONAL='TRUE';
      INPUT_LOAD='(-0.01,0.01)';
      OUTPUT_LOAD='(1.0,-1.0)';
    'MH1':
      PIN_NUMBER='(MH1,0)';
      PIN_TYPE='GROUND';
      NO_LOAD_CHECK='BOTH';
      NO_IO_CHECK='BOTH';
      ALLOW_CONNECT='TRUE';
    'MH2':
      PIN_NUMBER='(MH2,0)';
      PIN_TYPE='GROUND';
      NO_LOAD_CHECK='BOTH';
      NO_IO_CHECK='BOTH';
      ALLOW_CONNECT='TRUE';
  end_pin;
  body
    PART_NAME='SCONN200_H68296001';
    PHYS_DES_PREFIX='J';
     end_body;
end_primitive;

END.
